(kicad_pcb
	(version 20260206)
	(generator "pcbnew")
	(generator_version "10.0")
	(general
		(thickness 1.6)
		(legacy_teardrops no)
	)
	(paper "A4")
	(title_block
		(title "peb — Lightning_PEB_BRD.brd")
		(comment 1 "Lightning (Wiwynn / Facebook NVMe JBOF) / footprints 2372-2378 of 2563")
	)
	(layers
		(0 "F.Cu" signal "TOP")
		(4 "In1.Cu" signal "L2GND")
		(6 "In2.Cu" signal "L3")
		(8 "In3.Cu" signal "L4VCC")
		(10 "In4.Cu" signal "L5VCC")
		(12 "In5.Cu" signal "L6")
		(14 "In6.Cu" signal "L7GND")
		(2 "B.Cu" signal "BOTTOM")
		(9 "F.Adhes" user "F.Adhesive")
		(11 "B.Adhes" user "B.Adhesive")
		(13 "F.Paste" user "Package Geometry/Pastemask Top")
		(15 "B.Paste" user "Package Geometry/Pastemask Bottom")
		(5 "F.SilkS" user "Ref Des/Silkscreen Top")
		(7 "B.SilkS" user "Ref Des/Silkscreen Bottom")
		(1 "F.Mask" user "Board Geometry/Soldermask Top")
		(3 "B.Mask" user "Board Geometry/Soldermask Bottom")
		(17 "Dwgs.User" user "User.Drawings")
		(19 "Cmts.User" user "User.Comments")
		(21 "Eco1.User" user "User.Eco1")
		(23 "Eco2.User" user "User.Eco2")
		(25 "Edge.Cuts" user "Board Geometry/Outline")
		(27 "Margin" user)
		(31 "F.CrtYd" user "Package Geometry/Place Bound Top")
		(29 "B.CrtYd" user "Package Geometry/Place Bound Bottom")
		(35 "F.Fab" user "Ref Des/Assembly Top")
		(33 "B.Fab" user "Ref Des/Assembly Bottom")
	)
	(footprint ""
		(layer "B.Cu")
		(at 49.1744 -113.1316)
		(property "Reference" "R433"
			(at 0 0 0)
			(layer "B.SilkS")
			(hide yes)
			(effects
				(font
					(size 1.27 1.27)
				)
				(justify mirror)
			)
		)
		(property "Value" "4K7R2F-GP"
			(at -0.064008 -3.993896 0)
			(unlocked yes)
			(layer "B.Fab")
			(hide yes)
			(effects
				(font
					(size 1.016 1.016)
					(thickness 0.1524)
				)
				(justify mirror)
			)
		)
		(property "Device Type" "R402H16"
			(at -0.064008 -5.517896 0)
			(unlocked yes)
			(layer "B.Fab")
			(hide yes)
			(effects
				(font
					(size 1.016 1.016)
					(thickness 0.1524)
				)
				(justify mirror)
			)
		)
		(duplicate_pad_numbers_are_jumpers no)
		(fp_line
			(start -0.508 -0.9398)
			(end 0.508 -0.9398)
			(stroke
				(width 0.1524)
				(type default)
			)
			(layer "B.SilkS")
		)
		(fp_line
			(start 0.508 -0.9398)
			(end 0.508 0.9398)
			(stroke
				(width 0.1524)
				(type default)
			)
			(layer "B.SilkS")
		)
		(fp_rect
			(start 0.508 0.9398)
			(end -0.508 -0.9398)
			(stroke
				(width 0)
				(type default)
			)
			(fill no)
			(layer "B.CrtYd")
		)
		(fp_rect
			(start 0.508 0.9398)
			(end -0.508 -0.9398)
			(stroke
				(width 0)
				(type default)
			)
			(fill no)
			(layer "B.Fab")
		)
		(pad "1" smd custom
			(at 0 -0.4445 180)
			(size 0.1397 0.1397)
			(layers "B.Cu" "B.Mask" "B.Paste")
			(net "BMC_I2C9_CLKBUF2_SDA")
			(options
				(clearance outline)
				(anchor circle)
			)
			(primitives
				(gr_poly
					(pts
						(arc
							(start -0.1778 0.2794)
							(mid -0.249642 0.249642)
							(end -0.2794 0.1778)
						)
						(arc
							(start -0.2794 -0.1778)
							(mid -0.249642 -0.249642)
							(end -0.1778 -0.2794)
						)
						(arc
							(start 0.1778 -0.2794)
							(mid 0.249642 -0.249642)
							(end 0.2794 -0.1778)
						)
						(arc
							(start 0.2794 0.1778)
							(mid 0.249642 0.249642)
							(end 0.1778 0.2794)
						)
					)
					(width 0)
					(fill yes)
				)
			)
		)
		(pad "2" smd custom
			(at 0 0.4445 180)
			(size 0.1397 0.1397)
			(layers "B.Cu" "B.Mask" "B.Paste")
			(net "P3V3_STBY")
			(options
				(clearance outline)
				(anchor circle)
			)
			(primitives
				(gr_poly
					(pts
						(arc
							(start -0.1778 0.2794)
							(mid -0.249642 0.249642)
							(end -0.2794 0.1778)
						)
						(arc
							(start -0.2794 -0.1778)
							(mid -0.249642 -0.249642)
							(end -0.1778 -0.2794)
						)
						(arc
							(start 0.1778 -0.2794)
							(mid 0.249642 -0.249642)
							(end 0.2794 -0.1778)
						)
						(arc
							(start 0.2794 0.1778)
							(mid 0.249642 0.249642)
							(end 0.1778 0.2794)
						)
					)
					(width 0)
					(fill yes)
				)
			)
		)
	)
	(footprint ""
		(layer "B.Cu")
		(at 337.7946 -181.8386)
		(property "Reference" "R3228"
			(at 0 0 0)
			(layer "B.SilkS")
			(hide yes)
			(effects
				(font
					(size 1.27 1.27)
				)
				(justify mirror)
			)
		)
		(property "Value" "0R2J-2-GP"
			(at -0.064008 -3.993896 0)
			(unlocked yes)
			(layer "B.Fab")
			(hide yes)
			(effects
				(font
					(size 1.016 1.016)
					(thickness 0.1524)
				)
				(justify mirror)
			)
		)
		(property "Device Type" "R402H16"
			(at -0.064008 -5.517896 0)
			(unlocked yes)
			(layer "B.Fab")
			(hide yes)
			(effects
				(font
					(size 1.016 1.016)
					(thickness 0.1524)
				)
				(justify mirror)
			)
		)
		(duplicate_pad_numbers_are_jumpers no)
		(fp_line
			(start -0.508 -0.9398)
			(end 0.508 -0.9398)
			(stroke
				(width 0.1524)
				(type default)
			)
			(layer "B.SilkS")
		)
		(fp_line
			(start 0.508 -0.9398)
			(end 0.508 0.9398)
			(stroke
				(width 0.1524)
				(type default)
			)
			(layer "B.SilkS")
		)
		(fp_rect
			(start 0.508 0.9398)
			(end -0.508 -0.9398)
			(stroke
				(width 0)
				(type default)
			)
			(fill no)
			(layer "B.CrtYd")
		)
		(fp_rect
			(start 0.508 0.9398)
			(end -0.508 -0.9398)
			(stroke
				(width 0)
				(type default)
			)
			(fill no)
			(layer "B.Fab")
		)
		(pad "1" smd custom
			(at 0 -0.4445 180)
			(size 0.1397 0.1397)
			(layers "B.Cu" "B.Mask" "B.Paste")
			(net "SSD_PERST#9")
			(options
				(clearance outline)
				(anchor circle)
			)
			(primitives
				(gr_poly
					(pts
						(arc
							(start -0.1778 0.2794)
							(mid -0.249642 0.249642)
							(end -0.2794 0.1778)
						)
						(arc
							(start -0.2794 -0.1778)
							(mid -0.249642 -0.249642)
							(end -0.1778 -0.2794)
						)
						(arc
							(start 0.1778 -0.2794)
							(mid 0.249642 -0.249642)
							(end 0.2794 -0.1778)
						)
						(arc
							(start 0.2794 0.1778)
							(mid 0.249642 0.249642)
							(end 0.1778 0.2794)
						)
					)
					(width 0)
					(fill yes)
				)
			)
		)
		(pad "2" smd custom
			(at 0 0.4445 180)
			(size 0.1397 0.1397)
			(layers "B.Cu" "B.Mask" "B.Paste")
			(net "SSD_PERST#0_B9")
			(options
				(clearance outline)
				(anchor circle)
			)
			(primitives
				(gr_poly
					(pts
						(arc
							(start -0.1778 0.2794)
							(mid -0.249642 0.249642)
							(end -0.2794 0.1778)
						)
						(arc
							(start -0.2794 -0.1778)
							(mid -0.249642 -0.249642)
							(end -0.1778 -0.2794)
						)
						(arc
							(start 0.1778 -0.2794)
							(mid 0.249642 -0.249642)
							(end 0.2794 -0.1778)
						)
						(arc
							(start 0.2794 0.1778)
							(mid 0.249642 0.249642)
							(end 0.1778 0.2794)
						)
					)
					(width 0)
					(fill yes)
				)
			)
		)
	)
	(footprint ""
		(layer "B.Cu")
		(at 232.59542 -60.1218)
		(property "Reference" "C604"
			(at 0 0 0)
			(layer "B.SilkS")
			(hide yes)
			(effects
				(font
					(size 1.27 1.27)
				)
				(justify mirror)
			)
		)
		(property "Value" "SCD1U16V1KX-1-GP"
			(at 2.8321 -1.7399 0)
			(unlocked yes)
			(layer "B.Fab")
			(hide yes)
			(effects
				(font
					(size 1.016 1.016)
					(thickness 0.1524)
				)
				(justify mirror)
			)
		)
		(property "Device Type" "C0201H13"
			(at 2.8321 -3.2639 0)
			(unlocked yes)
			(layer "B.Fab")
			(hide yes)
			(effects
				(font
					(size 1.016 1.016)
					(thickness 0.1524)
				)
				(justify mirror)
			)
		)
		(duplicate_pad_numbers_are_jumpers no)
		(fp_rect
			(start 0.2794 0.6477)
			(end -0.2794 -0.6477)
			(stroke
				(width 0)
				(type default)
			)
			(fill no)
			(layer "B.CrtYd")
		)
		(fp_rect
			(start 0.2794 0.6477)
			(end -0.2794 -0.6477)
			(stroke
				(width 0)
				(type default)
			)
			(fill no)
			(layer "B.Fab")
		)
		(pad "1" smd custom
			(at 0 -0.2794 180)
			(size 0.0762 0.0762)
			(layers "B.Cu" "B.Mask" "B.Paste")
			(net "DUT_AVD_PCIE")
			(options
				(clearance outline)
				(anchor circle)
			)
			(primitives
				(gr_poly
					(pts
						(arc
							(start 0.1524 0.127)
							(mid 0.137521 0.162921)
							(end 0.1016 0.1778)
						)
						(arc
							(start -0.1016 0.1778)
							(mid -0.137521 0.162921)
							(end -0.1524 0.127)
						)
						(arc
							(start -0.1524 -0.127)
							(mid -0.137521 -0.162921)
							(end -0.1016 -0.1778)
						)
						(arc
							(start 0.1016 -0.1778)
							(mid 0.137521 -0.162921)
							(end 0.1524 -0.127)
						)
					)
					(width 0)
					(fill yes)
				)
			)
		)
		(pad "2" smd custom
			(at 0 0.2794 180)
			(size 0.0762 0.0762)
			(layers "B.Cu" "B.Mask" "B.Paste")
			(net "GND")
			(options
				(clearance outline)
				(anchor circle)
			)
			(primitives
				(gr_poly
					(pts
						(arc
							(start 0.1524 0.127)
							(mid 0.137521 0.162921)
							(end 0.1016 0.1778)
						)
						(arc
							(start -0.1016 0.1778)
							(mid -0.137521 0.162921)
							(end -0.1524 0.127)
						)
						(arc
							(start -0.1524 -0.127)
							(mid -0.137521 -0.162921)
							(end -0.1016 -0.1778)
						)
						(arc
							(start 0.1016 -0.1778)
							(mid 0.137521 -0.162921)
							(end 0.1524 -0.127)
						)
					)
					(width 0)
					(fill yes)
				)
			)
		)
	)
	(footprint ""
		(layer "B.Cu")
		(at 82.55 -189.611)
		(property "Reference" "U74"
			(at 0 0 0)
			(layer "B.SilkS")
			(hide yes)
			(effects
				(font
					(size 1.27 1.27)
				)
				(justify mirror)
			)
		)
		(property "Value" "SN74LVC1G08DCKR-GP"
			(at 2.3368 -8.6868 0)
			(unlocked yes)
			(layer "B.Fab")
			(hide yes)
			(effects
				(font
					(size 1.016 1.016)
					(thickness 0.1524)
				)
				(justify mirror)
			)
		)
		(property "Device Type" "SC70-5H44"
			(at 2.3114 -10.414 0)
			(unlocked yes)
			(layer "B.Fab")
			(hide yes)
			(effects
				(font
					(size 1.016 1.016)
					(thickness 0.1524)
				)
				(justify mirror)
			)
		)
		(duplicate_pad_numbers_are_jumpers no)
		(fp_line
			(start -1.3843 -1.8034)
			(end -1.3843 -1.1176)
			(stroke
				(width 0.3302)
				(type default)
			)
			(layer "B.SilkS")
		)
		(fp_line
			(start -1.27 -1.7018)
			(end -1.27 1.7018)
			(stroke
				(width 0.1524)
				(type default)
			)
			(layer "B.SilkS")
		)
		(fp_line
			(start -1.27 1.7018)
			(end 1.27 1.7018)
			(stroke
				(width 0.1524)
				(type default)
			)
			(layer "B.SilkS")
		)
		(fp_line
			(start -0.6604 -1.8034)
			(end -1.3843 -1.8034)
			(stroke
				(width 0.3302)
				(type default)
			)
			(layer "B.SilkS")
		)
		(fp_line
			(start 1.27 -1.7018)
			(end -1.27 -1.7018)
			(stroke
				(width 0.1524)
				(type default)
			)
			(layer "B.SilkS")
		)
		(fp_line
			(start 1.27 1.7018)
			(end 1.27 -1.7018)
			(stroke
				(width 0.1524)
				(type default)
			)
			(layer "B.SilkS")
		)
		(fp_rect
			(start 1.524 1.9558)
			(end -1.524 -1.9558)
			(stroke
				(width 0)
				(type default)
			)
			(fill no)
			(layer "B.CrtYd")
		)
		(fp_poly
			(pts
				(xy 1.524 -1.9558) (xy -1.524 -1.9558) (xy -1.524 1.9558) (xy 1.524 1.9558)
			)
			(stroke
				(width 0)
				(type default)
			)
			(fill no)
			(layer "B.Fab")
		)
		(pad "1" smd rect
			(at -0.65024 -0.8255 180)
			(size 0.4064 1.2192)
			(layers "B.Cu" "B.Mask" "B.Paste")
			(net "BMC_SSD_RST#0_A10")
		)
		(pad "2" smd rect
			(at 0 -0.8255 180)
			(size 0.4064 1.2192)
			(layers "B.Cu" "B.Mask" "B.Paste")
			(net "SSD_PERST#0_B10")
		)
		(pad "3" smd rect
			(at 0.65024 -0.8255 180)
			(size 0.4064 1.2192)
			(layers "B.Cu" "B.Mask" "B.Paste")
			(net "GND")
		)
		(pad "4" smd rect
			(at 0.65024 0.8255 180)
			(size 0.4064 1.2192)
			(layers "B.Cu" "B.Mask" "B.Paste")
			(net "SSD_PERST_Y10")
		)
		(pad "5" smd rect
			(at -0.65024 0.8255 180)
			(size 0.4064 1.2192)
			(layers "B.Cu" "B.Mask" "B.Paste")
			(net "P3V3_STBY")
		)
	)
	(footprint ""
		(layer "B.Cu")
		(at 178.0794 -65.405)
		(property "Reference" "PG22"
			(at 0 0 0)
			(layer "B.SilkS")
			(hide yes)
			(effects
				(font
					(size 1.27 1.27)
				)
				(justify mirror)
			)
		)
		(property "Value" "GAP-CLOSE-PWR-3-GP"
			(at -0.0254 -6.5786 0)
			(unlocked yes)
			(layer "B.Fab")
			(hide yes)
			(effects
				(font
					(size 1.016 1.016)
					(thickness 0.1524)
				)
				(justify mirror)
			)
		)
		(property "Device Type" "GAP-CLOSE-PWR-3"
			(at -0.0254 -8.255 0)
			(unlocked yes)
			(layer "B.Fab")
			(hide yes)
			(effects
				(font
					(size 1.016 1.016)
					(thickness 0.1524)
				)
				(justify mirror)
			)
		)
		(duplicate_pad_numbers_are_jumpers no)
		(fp_rect
			(start 0.7112 0.4572)
			(end -0.7112 -0.4572)
			(stroke
				(width 0)
				(type default)
			)
			(fill no)
			(layer "B.CrtYd")
		)
		(fp_poly
			(pts
				(xy 0.7112 -0.4572) (xy -0.7112 -0.4572) (xy -0.7112 0.4572) (xy 0.7112 0.4572)
			)
			(stroke
				(width 0)
				(type default)
			)
			(fill no)
			(layer "B.Fab")
		)
		(pad "1" smd rect
			(at 0.3048 0 180)
			(size 0.6604 0.762)
			(layers "B.Cu" "B.Mask" "B.Paste")
			(net "DUT_AVD_PCIE")
		)
		(pad "2" smd rect
			(at -0.3048 0 180)
			(size 0.6604 0.762)
			(layers "B.Cu" "B.Mask" "B.Paste")
			(net "P0V9")
		)
	)
	(footprint ""
		(layer "B.Cu")
		(at 217.66276 -200.71588 90)
		(property "Reference" "R3211"
			(at 0 0 90)
			(layer "B.SilkS")
			(hide yes)
			(effects
				(font
					(size 1.27 1.27)
				)
				(justify mirror)
			)
		)
		(property "Value" "0R2J-2-GP"
			(at -0.064008 -3.993896 90)
			(unlocked yes)
			(layer "B.Fab")
			(hide yes)
			(effects
				(font
					(size 1.016 1.016)
					(thickness 0.1524)
				)
				(justify mirror)
			)
		)
		(property "Device Type" "R402H16"
			(at -0.064008 -5.517896 90)
			(unlocked yes)
			(layer "B.Fab")
			(hide yes)
			(effects
				(font
					(size 1.016 1.016)
					(thickness 0.1524)
				)
				(justify mirror)
			)
		)
		(duplicate_pad_numbers_are_jumpers no)
		(fp_line
			(start 0.508 -0.9398)
			(end 0.508 0.9398)
			(stroke
				(width 0.1524)
				(type default)
			)
			(layer "B.SilkS")
		)
		(fp_line
			(start -0.508 -0.9398)
			(end 0.508 -0.9398)
			(stroke
				(width 0.1524)
				(type default)
			)
			(layer "B.SilkS")
		)
		(fp_rect
			(start 0.508 0.9398)
			(end -0.508 -0.9398)
			(stroke
				(width 0)
				(type default)
			)
			(fill no)
			(layer "B.CrtYd")
		)
		(fp_rect
			(start 0.508 0.9398)
			(end -0.508 -0.9398)
			(stroke
				(width 0)
				(type default)
			)
			(fill no)
			(layer "B.Fab")
		)
		(pad "1" smd custom
			(at 0 -0.4445 270)
			(size 0.1397 0.1397)
			(layers "B.Cu" "B.Mask" "B.Paste")
			(net "BMC_SSD_RST#3")
			(options
				(clearance outline)
				(anchor circle)
			)
			(primitives
				(gr_poly
					(pts
						(arc
							(start -0.1778 0.2794)
							(mid -0.249642 0.249642)
							(end -0.2794 0.1778)
						)
						(arc
							(start -0.2794 -0.1778)
							(mid -0.249642 -0.249642)
							(end -0.1778 -0.2794)
						)
						(arc
							(start 0.1778 -0.2794)
							(mid 0.249642 -0.249642)
							(end 0.2794 -0.1778)
						)
						(arc
							(start 0.2794 0.1778)
							(mid 0.249642 0.249642)
							(end 0.1778 0.2794)
						)
					)
					(width 0)
					(fill yes)
				)
			)
		)
		(pad "2" smd custom
			(at 0 0.4445 270)
			(size 0.1397 0.1397)
			(layers "B.Cu" "B.Mask" "B.Paste")
			(net "BMC_SSD_RST#0_A3")
			(options
				(clearance outline)
				(anchor circle)
			)
			(primitives
				(gr_poly
					(pts
						(arc
							(start -0.1778 0.2794)
							(mid -0.249642 0.249642)
							(end -0.2794 0.1778)
						)
						(arc
							(start -0.2794 -0.1778)
							(mid -0.249642 -0.249642)
							(end -0.1778 -0.2794)
						)
						(arc
							(start 0.1778 -0.2794)
							(mid 0.249642 -0.249642)
							(end 0.2794 -0.1778)
						)
						(arc
							(start 0.2794 0.1778)
							(mid 0.249642 0.249642)
							(end 0.1778 0.2794)
						)
					)
					(width 0)
					(fill yes)
				)
			)
		)
	)
	(footprint ""
		(layer "B.Cu")
		(at 214.58174 -200.04786)
		(property "Reference" "R3240"
			(at 0 0 0)
			(layer "B.SilkS")
			(hide yes)
			(effects
				(font
					(size 1.27 1.27)
				)
				(justify mirror)
			)
		)
		(property "Value" "0R2J-2-GP"
			(at -0.064008 -3.993896 0)
			(unlocked yes)
			(layer "B.Fab")
			(hide yes)
			(effects
				(font
					(size 1.016 1.016)
					(thickness 0.1524)
				)
				(justify mirror)
			)
		)
		(property "Device Type" "R402H16"
			(at -0.064008 -5.517896 0)
			(unlocked yes)
			(layer "B.Fab")
			(hide yes)
			(effects
				(font
					(size 1.016 1.016)
					(thickness 0.1524)
				)
				(justify mirror)
			)
		)
		(duplicate_pad_numbers_are_jumpers no)
		(fp_line
			(start -0.508 -0.9398)
			(end 0.508 -0.9398)
			(stroke
				(width 0.1524)
				(type default)
			)
			(layer "B.SilkS")
		)
		(fp_line
			(start 0.508 -0.9398)
			(end 0.508 0.9398)
			(stroke
				(width 0.1524)
				(type default)
			)
			(layer "B.SilkS")
		)
		(fp_rect
			(start 0.508 0.9398)
			(end -0.508 -0.9398)
			(stroke
				(width 0)
				(type default)
			)
			(fill no)
			(layer "B.CrtYd")
		)
		(fp_rect
			(start 0.508 0.9398)
			(end -0.508 -0.9398)
			(stroke
				(width 0)
				(type default)
			)
			(fill no)
			(layer "B.Fab")
		)
		(pad "1" smd custom
			(at 0 -0.4445 180)
			(size 0.1397 0.1397)
			(layers "B.Cu" "B.Mask" "B.Paste")
			(net "SSD_PERST#13")
			(options
				(clearance outline)
				(anchor circle)
			)
			(primitives
				(gr_poly
					(pts
						(arc
							(start -0.1778 0.2794)
							(mid -0.249642 0.249642)
							(end -0.2794 0.1778)
						)
						(arc
							(start -0.2794 -0.1778)
							(mid -0.249642 -0.249642)
							(end -0.1778 -0.2794)
						)
						(arc
							(start 0.1778 -0.2794)
							(mid 0.249642 -0.249642)
							(end 0.2794 -0.1778)
						)
						(arc
							(start 0.2794 0.1778)
							(mid 0.249642 0.249642)
							(end 0.1778 0.2794)
						)
					)
					(width 0)
					(fill yes)
				)
			)
		)
		(pad "2" smd custom
			(at 0 0.4445 180)
			(size 0.1397 0.1397)
			(layers "B.Cu" "B.Mask" "B.Paste")
			(net "SSD_PERST#0_B13")
			(options
				(clearance outline)
				(anchor circle)
			)
			(primitives
				(gr_poly
					(pts
						(arc
							(start -0.1778 0.2794)
							(mid -0.249642 0.249642)
							(end -0.2794 0.1778)
						)
						(arc
							(start -0.2794 -0.1778)
							(mid -0.249642 -0.249642)
							(end -0.1778 -0.2794)
						)
						(arc
							(start 0.1778 -0.2794)
							(mid 0.249642 -0.249642)
							(end 0.2794 -0.1778)
						)
						(arc
							(start 0.2794 0.1778)
							(mid 0.249642 0.249642)
							(end 0.1778 0.2794)
						)
					)
					(width 0)
					(fill yes)
				)
			)
		)
	)
)
